(kicad_pcb
	(version 20260206)
	(generator "pcbnew")
	(generator_version "10.0")
	(general
		(thickness 1.6)
		(legacy_teardrops no)
	)
	(paper "A4")
	(title_block
		(title "04192023_DAF0TMB3IC0_F0TG_MB_C_brd_V02_OCP.brd")
		(comment 1 "Grand Teton / footprints 397-402 of 8354")
	)
	(layers
		(0 "F.Cu" signal "TOP")
		(4 "In1.Cu" signal "GND")
		(6 "In2.Cu" signal "IN1")
		(8 "In3.Cu" signal "GND1")
		(10 "In4.Cu" signal "IN2")
		(12 "In5.Cu" signal "GND2")
		(14 "In6.Cu" signal "IN3")
		(16 "In7.Cu" signal "GND3")
		(18 "In8.Cu" signal "VCC")
		(20 "In9.Cu" signal "VCC1")
		(22 "In10.Cu" signal "GND4")
		(24 "In11.Cu" signal "IN4")
		(26 "In12.Cu" signal "GND5")
		(28 "In13.Cu" signal "IN5")
		(30 "In14.Cu" signal "GND6")
		(32 "In15.Cu" signal "IN6")
		(34 "In16.Cu" signal "GND7")
		(2 "B.Cu" signal "BOTTOM")
		(9 "F.Adhes" user "F.Adhesive")
		(11 "B.Adhes" user "B.Adhesive")
		(13 "F.Paste" user "Package Geometry/Pastemask Top")
		(15 "B.Paste" user "Package Geometry/Pastemask Bottom")
		(5 "F.SilkS" user "Ref Des/Silkscreen Top")
		(7 "B.SilkS" user "Ref Des/Silkscreen Bottom")
		(1 "F.Mask" user "Board Geometry/Soldermask Top")
		(3 "B.Mask" user "Board Geometry/Soldermask Bottom")
		(17 "Dwgs.User" user "User.Drawings")
		(19 "Cmts.User" user "User.Comments")
		(21 "Eco1.User" user "User.Eco1")
		(23 "Eco2.User" user "User.Eco2")
		(25 "Edge.Cuts" user "Board Geometry/Outline")
		(27 "Margin" user)
		(31 "F.CrtYd" user "Package Geometry/Place Bound Top")
		(29 "B.CrtYd" user "Package Geometry/Place Bound Bottom")
		(35 "F.Fab" user "Ref Des/Assembly Top")
		(33 "B.Fab" user "Ref Des/Assembly Bottom")
	)
	(footprint ""
		(layer "F.Cu")
		(at 172.9232 -94.833948 -90)
		(property "Reference" "R6015"
			(at 0 0 270)
			(layer "F.SilkS")
			(hide yes)
			(effects
				(font
					(size 1.27 1.27)
				)
			)
		)
		(property "Value" ""
			(at 0 0 270)
			(layer "F.Fab")
			(effects
				(font
					(size 1.27 1.27)
				)
			)
		)
		(duplicate_pad_numbers_are_jumpers no)
		(fp_line
			(start -0.7874 0.4064)
			(end -0.7874 -0.4064)
			(stroke
				(width 0.1524)
				(type default)
			)
			(layer "F.SilkS")
		)
		(fp_line
			(start 0.7874 0.4064)
			(end -0.7874 0.4064)
			(stroke
				(width 0.1524)
				(type default)
			)
			(layer "F.SilkS")
		)
		(fp_line
			(start -0.7874 -0.4064)
			(end 0.7874 -0.4064)
			(stroke
				(width 0.1524)
				(type default)
			)
			(layer "F.SilkS")
		)
		(fp_line
			(start 0.7874 -0.4064)
			(end 0.7874 0.4064)
			(stroke
				(width 0.1524)
				(type default)
			)
			(layer "F.SilkS")
		)
		(fp_line
			(start -0.67945 0.3048)
			(end -0.67945 -0.305054)
			(stroke
				(width 0.1)
				(type default)
			)
			(layer "F.Fab")
		)
		(fp_line
			(start -0.12065 0.3048)
			(end -0.67945 0.3048)
			(stroke
				(width 0.1)
				(type default)
			)
			(layer "F.Fab")
		)
		(fp_line
			(start 0.120396 0.3048)
			(end 0.120396 0.2794)
			(stroke
				(width 0.1)
				(type default)
			)
			(layer "F.Fab")
		)
		(fp_line
			(start 0.67945 0.3048)
			(end 0.120396 0.3048)
			(stroke
				(width 0.1)
				(type default)
			)
			(layer "F.Fab")
		)
		(fp_line
			(start -0.12065 0.2794)
			(end -0.12065 0.3048)
			(stroke
				(width 0.1)
				(type default)
			)
			(layer "F.Fab")
		)
		(fp_line
			(start 0.120396 0.2794)
			(end -0.12065 0.2794)
			(stroke
				(width 0.1)
				(type default)
			)
			(layer "F.Fab")
		)
		(fp_line
			(start -0.12065 -0.2794)
			(end 0.12065 -0.2794)
			(stroke
				(width 0.1)
				(type default)
			)
			(layer "F.Fab")
		)
		(fp_line
			(start 0.12065 -0.2794)
			(end 0.12065 -0.3048)
			(stroke
				(width 0.1)
				(type default)
			)
			(layer "F.Fab")
		)
		(fp_line
			(start 0.12065 -0.3048)
			(end 0.67945 -0.3048)
			(stroke
				(width 0.1)
				(type default)
			)
			(layer "F.Fab")
		)
		(fp_line
			(start 0.67945 -0.3048)
			(end 0.67945 0.3048)
			(stroke
				(width 0.1)
				(type default)
			)
			(layer "F.Fab")
		)
		(fp_line
			(start -0.67945 -0.305054)
			(end -0.12065 -0.305054)
			(stroke
				(width 0.1)
				(type default)
			)
			(layer "F.Fab")
		)
		(fp_line
			(start -0.12065 -0.305054)
			(end -0.12065 -0.2794)
			(stroke
				(width 0.1)
				(type default)
			)
			(layer "F.Fab")
		)
		(pad "1" smd circle
			(at -0.40005 0 270)
			(size 0 0)
			(layers "F.Cu" "F.Mask" "F.Paste")
			(net "SGPIO_SCM_LD_<1>")
		)
		(pad "2" smd circle
			(at 0.40005 0 270)
			(size 0 0)
			(layers "F.Cu" "F.Mask" "F.Paste")
			(net "SGPIO_SCM_LD_R_<1>")
		)
	)
	(footprint ""
		(layer "F.Cu")
		(at 112.024922 -431.360072 180)
		(property "Reference" "J123"
			(at 1.199134 -11.256772 0)
			(unlocked yes)
			(layer "F.SilkS")
			(effects
				(font
					(size 0.7874 0.5842)
					(thickness 0.1524)
				)
				(justify left)
			)
		)
		(property "Value" ""
			(at 0 0 180)
			(layer "F.Fab")
			(effects
				(font
					(size 1.27 1.27)
				)
			)
		)
		(duplicate_pad_numbers_are_jumpers no)
		(fp_line
			(start 3.525012 9.614408)
			(end 3.525012 6.154928)
			(stroke
				(width 0.1524)
				(type default)
			)
			(layer "F.SilkS")
		)
		(fp_line
			(start 3.525012 2.344928)
			(end 3.525012 -10.489946)
			(stroke
				(width 0.1524)
				(type default)
			)
			(layer "F.SilkS")
		)
		(fp_line
			(start 3.525012 -10.489946)
			(end -3.525012 -10.489946)
			(stroke
				(width 0.1524)
				(type default)
			)
			(layer "F.SilkS")
		)
		(fp_line
			(start -3.525012 -10.489946)
			(end -3.525012 9.614408)
			(stroke
				(width 0.1524)
				(type default)
			)
			(layer "F.SilkS")
		)
		(fp_line
			(start 3.525012 21.310092)
			(end 3.525012 -10.489946)
			(stroke
				(width 0.1)
				(type default)
			)
			(layer "F.Fab")
		)
		(fp_line
			(start 3.525012 -10.489946)
			(end -3.525012 -10.489946)
			(stroke
				(width 0.1)
				(type default)
			)
			(layer "F.Fab")
		)
		(fp_line
			(start -3.525012 21.310092)
			(end 3.525012 21.310092)
			(stroke
				(width 0.1)
				(type default)
			)
			(layer "F.Fab")
		)
		(fp_line
			(start -3.525012 -10.489946)
			(end -3.525012 21.310092)
			(stroke
				(width 0.1)
				(type default)
			)
			(layer "F.Fab")
		)
		(pad "" np_thru_hole circle
			(at 0 -6.620002 180)
			(size 3.175 3.175)
			(drill 3.175)
			(layers "*.Cu" "*.Mask")
			(clearance 0.381)
			(thermal_gap 0.381)
		)
		(pad "" np_thru_hole circle
			(at 0 0 180)
			(size 0 0)
			(drill 3.175)
			(layers "*.Cu" "*.Mask")
			(clearance 0)
		)
		(pad "" np_thru_hole circle
			(at 0 5.130038 180)
			(size 3.175 3.175)
			(drill 3.175)
			(layers "*.Cu" "*.Mask")
			(clearance 0.381)
			(thermal_gap 0.381)
		)
		(zone
			(layers "F.Cu" "B.Cu" "In1.Cu" "In2.Cu" "In3.Cu" "In4.Cu" "In5.Cu" "In6.Cu"
				"In7.Cu" "In8.Cu" "In9.Cu" "In10.Cu" "In11.Cu" "In12.Cu" "In13.Cu" "In14.Cu"
				"In15.Cu" "In16.Cu"
			)
			(hatch none 0.5)
			(connect_pads
				(clearance 0)
			)
			(min_thickness 0.25)
			(keepout
				(tracks not_allowed)
				(vias allowed)
				(pads allowed)
				(copperpour not_allowed)
				(footprints allowed)
			)
			(placement
				(enabled no)
				(sheetname "")
			)
			(fill
				(thermal_gap 0.5)
				(thermal_bridge_width 0.5)
				(island_removal_mode 0)
			)
			(polygon
				(pts
					(arc
						(start 114.120422 -436.49011)
						(mid 109.929422 -436.49011)
						(end 114.120422 -436.49011)
					)
				)
			)
		)
		(zone
			(layers "F.Cu" "B.Cu" "In1.Cu" "In2.Cu" "In3.Cu" "In4.Cu" "In5.Cu" "In6.Cu"
				"In7.Cu" "In8.Cu" "In9.Cu" "In10.Cu" "In11.Cu" "In12.Cu" "In13.Cu" "In14.Cu"
				"In15.Cu" "In16.Cu"
			)
			(hatch none 0.5)
			(connect_pads
				(clearance 0)
			)
			(min_thickness 0.25)
			(keepout
				(tracks not_allowed)
				(vias allowed)
				(pads allowed)
				(copperpour not_allowed)
				(footprints allowed)
			)
			(placement
				(enabled no)
				(sheetname "")
			)
			(fill
				(thermal_gap 0.5)
				(thermal_bridge_width 0.5)
				(island_removal_mode 0)
			)
			(polygon
				(pts
					(arc
						(start 114.120422 -424.74007)
						(mid 109.929422 -424.74007)
						(end 114.120422 -424.74007)
					)
				)
			)
		)
		(zone
			(layers "F.Cu" "B.Cu" "In1.Cu" "In2.Cu" "In3.Cu" "In4.Cu" "In5.Cu" "In6.Cu"
				"In7.Cu" "In8.Cu" "In9.Cu" "In10.Cu" "In11.Cu" "In12.Cu" "In13.Cu" "In14.Cu"
				"In15.Cu" "In16.Cu"
			)
			(hatch none 0.5)
			(connect_pads
				(clearance 0)
			)
			(min_thickness 0.25)
			(keepout
				(tracks not_allowed)
				(vias allowed)
				(pads allowed)
				(copperpour not_allowed)
				(footprints allowed)
			)
			(placement
				(enabled no)
				(sheetname "")
			)
			(fill
				(thermal_gap 0.5)
				(thermal_bridge_width 0.5)
				(island_removal_mode 0)
			)
			(polygon
				(pts
					(arc
						(start 115.644422 -431.360072)
						(mid 108.405422 -431.360072)
						(end 115.644422 -431.360072)
					)
				)
			)
		)
	)
	(footprint ""
		(layer "F.Cu")
		(at 443.89294 -77.496924)
		(property "Reference" "C61"
			(at 0 0 0)
			(layer "F.SilkS")
			(hide yes)
			(effects
				(font
					(size 1.27 1.27)
				)
			)
		)
		(property "Value" ""
			(at 0 0 0)
			(layer "F.Fab")
			(effects
				(font
					(size 1.27 1.27)
				)
			)
		)
		(duplicate_pad_numbers_are_jumpers no)
		(fp_line
			(start -0.7874 -0.4064)
			(end 0.7874 -0.4064)
			(stroke
				(width 0.1524)
				(type default)
			)
			(layer "F.SilkS")
		)
		(fp_line
			(start -0.7874 0.4064)
			(end -0.7874 -0.4064)
			(stroke
				(width 0.1524)
				(type default)
			)
			(layer "F.SilkS")
		)
		(fp_line
			(start 0.7874 -0.4064)
			(end 0.7874 0.4064)
			(stroke
				(width 0.1524)
				(type default)
			)
			(layer "F.SilkS")
		)
		(fp_line
			(start 0.7874 0.4064)
			(end -0.7874 0.4064)
			(stroke
				(width 0.1524)
				(type default)
			)
			(layer "F.SilkS")
		)
		(fp_line
			(start -0.67945 -0.305054)
			(end -0.12065 -0.305054)
			(stroke
				(width 0.1)
				(type default)
			)
			(layer "F.Fab")
		)
		(fp_line
			(start -0.67945 0.3048)
			(end -0.67945 -0.305054)
			(stroke
				(width 0.1)
				(type default)
			)
			(layer "F.Fab")
		)
		(fp_line
			(start -0.12065 -0.305054)
			(end -0.12065 -0.2794)
			(stroke
				(width 0.1)
				(type default)
			)
			(layer "F.Fab")
		)
		(fp_line
			(start -0.12065 -0.2794)
			(end 0.12065 -0.2794)
			(stroke
				(width 0.1)
				(type default)
			)
			(layer "F.Fab")
		)
		(fp_line
			(start -0.12065 0.2794)
			(end -0.12065 0.3048)
			(stroke
				(width 0.1)
				(type default)
			)
			(layer "F.Fab")
		)
		(fp_line
			(start -0.12065 0.3048)
			(end -0.67945 0.3048)
			(stroke
				(width 0.1)
				(type default)
			)
			(layer "F.Fab")
		)
		(fp_line
			(start 0.120396 0.2794)
			(end -0.12065 0.2794)
			(stroke
				(width 0.1)
				(type default)
			)
			(layer "F.Fab")
		)
		(fp_line
			(start 0.120396 0.3048)
			(end 0.120396 0.2794)
			(stroke
				(width 0.1)
				(type default)
			)
			(layer "F.Fab")
		)
		(fp_line
			(start 0.12065 -0.3048)
			(end 0.67945 -0.3048)
			(stroke
				(width 0.1)
				(type default)
			)
			(layer "F.Fab")
		)
		(fp_line
			(start 0.12065 -0.2794)
			(end 0.12065 -0.3048)
			(stroke
				(width 0.1)
				(type default)
			)
			(layer "F.Fab")
		)
		(fp_line
			(start 0.67945 -0.3048)
			(end 0.67945 0.3048)
			(stroke
				(width 0.1)
				(type default)
			)
			(layer "F.Fab")
		)
		(fp_line
			(start 0.67945 0.3048)
			(end 0.120396 0.3048)
			(stroke
				(width 0.1)
				(type default)
			)
			(layer "F.Fab")
		)
		(pad "1" smd circle
			(at -0.40005 0)
			(size 0 0)
			(layers "F.Cu" "F.Mask" "F.Paste")
			(net "P3V3")
		)
		(pad "2" smd circle
			(at 0.40005 0)
			(size 0 0)
			(layers "F.Cu" "F.Mask" "F.Paste")
			(net "GND")
		)
	)
	(footprint ""
		(layer "F.Cu")
		(at 12.733782 -405.611584 -90)
		(property "Reference" "PC6546"
			(at 0 0 270)
			(layer "F.SilkS")
			(hide yes)
			(effects
				(font
					(size 1.27 1.27)
				)
			)
		)
		(property "Value" ""
			(at 0 0 270)
			(layer "F.Fab")
			(effects
				(font
					(size 1.27 1.27)
				)
			)
		)
		(duplicate_pad_numbers_are_jumpers no)
		(fp_line
			(start -0.7874 0.4064)
			(end -0.7874 -0.4064)
			(stroke
				(width 0.1524)
				(type default)
			)
			(layer "F.SilkS")
		)
		(fp_line
			(start 0.7874 0.4064)
			(end -0.7874 0.4064)
			(stroke
				(width 0.1524)
				(type default)
			)
			(layer "F.SilkS")
		)
		(fp_line
			(start -0.7874 -0.4064)
			(end 0.7874 -0.4064)
			(stroke
				(width 0.1524)
				(type default)
			)
			(layer "F.SilkS")
		)
		(fp_line
			(start 0.7874 -0.4064)
			(end 0.7874 0.4064)
			(stroke
				(width 0.1524)
				(type default)
			)
			(layer "F.SilkS")
		)
		(fp_line
			(start -0.67945 0.3048)
			(end -0.67945 -0.305054)
			(stroke
				(width 0.1)
				(type default)
			)
			(layer "F.Fab")
		)
		(fp_line
			(start -0.12065 0.3048)
			(end -0.67945 0.3048)
			(stroke
				(width 0.1)
				(type default)
			)
			(layer "F.Fab")
		)
		(fp_line
			(start 0.120396 0.3048)
			(end 0.120396 0.2794)
			(stroke
				(width 0.1)
				(type default)
			)
			(layer "F.Fab")
		)
		(fp_line
			(start 0.67945 0.3048)
			(end 0.120396 0.3048)
			(stroke
				(width 0.1)
				(type default)
			)
			(layer "F.Fab")
		)
		(fp_line
			(start -0.12065 0.2794)
			(end -0.12065 0.3048)
			(stroke
				(width 0.1)
				(type default)
			)
			(layer "F.Fab")
		)
		(fp_line
			(start 0.120396 0.2794)
			(end -0.12065 0.2794)
			(stroke
				(width 0.1)
				(type default)
			)
			(layer "F.Fab")
		)
		(fp_line
			(start -0.12065 -0.2794)
			(end 0.12065 -0.2794)
			(stroke
				(width 0.1)
				(type default)
			)
			(layer "F.Fab")
		)
		(fp_line
			(start 0.12065 -0.2794)
			(end 0.12065 -0.3048)
			(stroke
				(width 0.1)
				(type default)
			)
			(layer "F.Fab")
		)
		(fp_line
			(start 0.12065 -0.3048)
			(end 0.67945 -0.3048)
			(stroke
				(width 0.1)
				(type default)
			)
			(layer "F.Fab")
		)
		(fp_line
			(start 0.67945 -0.3048)
			(end 0.67945 0.3048)
			(stroke
				(width 0.1)
				(type default)
			)
			(layer "F.Fab")
		)
		(fp_line
			(start -0.67945 -0.305054)
			(end -0.12065 -0.305054)
			(stroke
				(width 0.1)
				(type default)
			)
			(layer "F.Fab")
		)
		(fp_line
			(start -0.12065 -0.305054)
			(end -0.12065 -0.2794)
			(stroke
				(width 0.1)
				(type default)
			)
			(layer "F.Fab")
		)
		(pad "1" smd circle
			(at -0.40005 0 270)
			(size 0 0)
			(layers "F.Cu" "F.Mask" "F.Paste")
			(net "PV09_RETIMER_CPU1_VCCS")
		)
		(pad "2" smd circle
			(at 0.40005 0 270)
			(size 0 0)
			(layers "F.Cu" "F.Mask" "F.Paste")
			(net "GND")
		)
	)
	(footprint ""
		(layer "F.Cu")
		(at 204.7621 -400.972782 180)
		(property "Reference" "PR3915"
			(at 0 0 180)
			(layer "F.SilkS")
			(hide yes)
			(effects
				(font
					(size 1.27 1.27)
				)
			)
		)
		(property "Value" ""
			(at 0 0 180)
			(layer "F.Fab")
			(effects
				(font
					(size 1.27 1.27)
				)
			)
		)
		(duplicate_pad_numbers_are_jumpers no)
		(fp_line
			(start 0.7874 0.4064)
			(end -0.7874 0.4064)
			(stroke
				(width 0.1524)
				(type default)
			)
			(layer "F.SilkS")
		)
		(fp_line
			(start 0.7874 -0.4064)
			(end 0.7874 0.4064)
			(stroke
				(width 0.1524)
				(type default)
			)
			(layer "F.SilkS")
		)
		(fp_line
			(start -0.7874 0.4064)
			(end -0.7874 -0.4064)
			(stroke
				(width 0.1524)
				(type default)
			)
			(layer "F.SilkS")
		)
		(fp_line
			(start -0.7874 -0.4064)
			(end 0.7874 -0.4064)
			(stroke
				(width 0.1524)
				(type default)
			)
			(layer "F.SilkS")
		)
		(fp_line
			(start 0.67945 0.3048)
			(end 0.120396 0.3048)
			(stroke
				(width 0.1)
				(type default)
			)
			(layer "F.Fab")
		)
		(fp_line
			(start 0.67945 -0.3048)
			(end 0.67945 0.3048)
			(stroke
				(width 0.1)
				(type default)
			)
			(layer "F.Fab")
		)
		(fp_line
			(start 0.12065 -0.2794)
			(end 0.12065 -0.3048)
			(stroke
				(width 0.1)
				(type default)
			)
			(layer "F.Fab")
		)
		(fp_line
			(start 0.12065 -0.3048)
			(end 0.67945 -0.3048)
			(stroke
				(width 0.1)
				(type default)
			)
			(layer "F.Fab")
		)
		(fp_line
			(start 0.120396 0.3048)
			(end 0.120396 0.2794)
			(stroke
				(width 0.1)
				(type default)
			)
			(layer "F.Fab")
		)
		(fp_line
			(start 0.120396 0.2794)
			(end -0.12065 0.2794)
			(stroke
				(width 0.1)
				(type default)
			)
			(layer "F.Fab")
		)
		(fp_line
			(start -0.12065 0.3048)
			(end -0.67945 0.3048)
			(stroke
				(width 0.1)
				(type default)
			)
			(layer "F.Fab")
		)
		(fp_line
			(start -0.12065 0.2794)
			(end -0.12065 0.3048)
			(stroke
				(width 0.1)
				(type default)
			)
			(layer "F.Fab")
		)
		(fp_line
			(start -0.12065 -0.2794)
			(end 0.12065 -0.2794)
			(stroke
				(width 0.1)
				(type default)
			)
			(layer "F.Fab")
		)
		(fp_line
			(start -0.12065 -0.305054)
			(end -0.12065 -0.2794)
			(stroke
				(width 0.1)
				(type default)
			)
			(layer "F.Fab")
		)
		(fp_line
			(start -0.67945 0.3048)
			(end -0.67945 -0.305054)
			(stroke
				(width 0.1)
				(type default)
			)
			(layer "F.Fab")
		)
		(fp_line
			(start -0.67945 -0.305054)
			(end -0.12065 -0.305054)
			(stroke
				(width 0.1)
				(type default)
			)
			(layer "F.Fab")
		)
		(pad "1" smd circle
			(at -0.40005 0 180)
			(size 0 0)
			(layers "F.Cu" "F.Mask" "F.Paste")
			(net "HSC_CS_2")
		)
		(pad "2" smd circle
			(at 0.40005 0 180)
			(size 0 0)
			(layers "F.Cu" "F.Mask" "F.Paste")
			(net "AGND_HSC")
		)
	)
	(footprint ""
		(layer "F.Cu")
		(at 383.557018 -154.771852 180)
		(property "Reference" "PL65"
			(at 2.980436 3.704844 0)
			(unlocked yes)
			(layer "F.SilkS")
			(effects
				(font
					(size 0.7874 0.5842)
					(thickness 0.1524)
				)
				(justify left)
			)
		)
		(property "Value" ""
			(at 0 0 180)
			(layer "F.Fab")
			(effects
				(font
					(size 1.27 1.27)
				)
			)
		)
		(duplicate_pad_numbers_are_jumpers no)
		(fp_line
			(start 3.050032 2.999994)
			(end 3.050032 1.4478)
			(stroke
				(width 0.1524)
				(type default)
			)
			(layer "F.SilkS")
		)
		(fp_line
			(start 3.050032 -1.4478)
			(end 3.050032 -2.999994)
			(stroke
				(width 0.1524)
				(type default)
			)
			(layer "F.SilkS")
		)
		(fp_line
			(start 3.050032 -2.999994)
			(end -3.050032 -2.999994)
			(stroke
				(width 0.1524)
				(type default)
			)
			(layer "F.SilkS")
		)
		(fp_line
			(start -3.050032 2.999994)
			(end 3.050032 2.999994)
			(stroke
				(width 0.1524)
				(type default)
			)
			(layer "F.SilkS")
		)
		(fp_line
			(start -3.050032 1.4478)
			(end -3.050032 2.999994)
			(stroke
				(width 0.1524)
				(type default)
			)
			(layer "F.SilkS")
		)
		(fp_line
			(start -3.050032 -2.999994)
			(end -3.050032 -1.4478)
			(stroke
				(width 0.1524)
				(type default)
			)
			(layer "F.SilkS")
		)
		(fp_line
			(start 3.050032 2.999994)
			(end 3.050032 -2.999994)
			(stroke
				(width 0.1)
				(type default)
			)
			(layer "F.Fab")
		)
		(fp_line
			(start 3.050032 -2.999994)
			(end -3.050032 -2.999994)
			(stroke
				(width 0.1)
				(type default)
			)
			(layer "F.Fab")
		)
		(fp_line
			(start -3.050032 2.999994)
			(end 3.050032 2.999994)
			(stroke
				(width 0.1)
				(type default)
			)
			(layer "F.Fab")
		)
		(fp_line
			(start -3.050032 -2.999994)
			(end -3.050032 2.999994)
			(stroke
				(width 0.1)
				(type default)
			)
			(layer "F.Fab")
		)
		(pad "1" smd rect
			(at -2.525014 0 180)
			(size 1.651 2.6162)
			(layers "F.Cu" "F.Mask" "F.Paste")
			(net "SW_P12V_AUX_PVDDCR_SOC_P0_FLT")
		)
		(pad "2" smd rect
			(at 2.525014 0 180)
			(size 1.651 2.6162)
			(layers "F.Cu" "F.Mask" "F.Paste")
			(net "P12V_AUX")
		)
	)
)
